# S9S_MB_2U (Grand Teton) — schematic netlist excerpt (pin names and nets, part order shuffled) for the footprints in the layout excerpt that follows; sources: Cadence DE-HDL packaged netlist, KiCad conversion of 03242023_DA0F0TMBIJ0_F0T_Motherboard_J_brd_V01_OCP.brd

R4094  Q_RES  4.7K 1% CHIP  pkg 0402LF  page 171 : A = P3V3_AUX ; B = OCP_SFF_P3V3_ADC_ALERT_R
C284  Q_CAP  22UF 4V 20% X6S  pkg C0402  page 77 : A = PVCCIN_CPU1 ; B = GND

(kicad_pcb
	(version 20260206)
	(generator "pcbnew")
	(generator_version "10.0")
	(general
		(thickness 1.6)
		(legacy_teardrops no)
	)
	(paper "A4")
	(title_block
		(title "03242023_DA0F0TMBIJ0_F0T_Motherboard_J_brd_V01_OCP.brd")
		(comment 1 "Grand Teton / footprints 2577-2578 of 6105")
	)
	(layers
		(0 "F.Cu" signal "TOP")
		(4 "In1.Cu" signal "GND")
		(6 "In2.Cu" signal "IN1")
		(8 "In3.Cu" signal "GND1")
		(10 "In4.Cu" signal "IN2")
		(12 "In5.Cu" signal "GND2")
		(14 "In6.Cu" signal "IN3")
		(16 "In7.Cu" signal "GND3")
		(18 "In8.Cu" signal "VCC")
		(20 "In9.Cu" signal "VCC1")
		(22 "In10.Cu" signal "GND4")
		(24 "In11.Cu" signal "IN4")
		(26 "In12.Cu" signal "GND5")
		(28 "In13.Cu" signal "IN5")
		(30 "In14.Cu" signal "GND6")
		(32 "In15.Cu" signal "IN6")
		(34 "In16.Cu" signal "GND7")
		(2 "B.Cu" signal "BOTTOM")
		(9 "F.Adhes" user "F.Adhesive")
		(11 "B.Adhes" user "B.Adhesive")
		(13 "F.Paste" user "Package Geometry/Pastemask Top")
		(15 "B.Paste" user "Package Geometry/Pastemask Bottom")
		(5 "F.SilkS" user "Ref Des/Silkscreen Top")
		(7 "B.SilkS" user "Ref Des/Silkscreen Bottom")
		(1 "F.Mask" user "Board Geometry/Soldermask Top")
		(3 "B.Mask" user "Board Geometry/Soldermask Bottom")
		(17 "Dwgs.User" user "User.Drawings")
		(19 "Cmts.User" user "User.Comments")
		(21 "Eco1.User" user "User.Eco1")
		(23 "Eco2.User" user "User.Eco2")
		(25 "Edge.Cuts" user "Board Geometry/Outline")
		(27 "Margin" user)
		(31 "F.CrtYd" user "Package Geometry/Place Bound Top")
		(29 "B.CrtYd" user "Package Geometry/Place Bound Bottom")
		(35 "F.Fab" user "Ref Des/Assembly Top")
		(33 "B.Fab" user "Ref Des/Assembly Bottom")
	)
	(footprint ""
		(layer "F.Cu")
		(at 107.28833 -241.97691 -90)
		(property "Reference" "C284"
			(at 0 0 270)
			(layer "F.SilkS")
			(hide yes)
			(effects
				(font
					(size 1.27 1.27)
				)
			)
		)
		(property "Value" ""
			(at 0 0 270)
			(layer "F.Fab")
			(effects
				(font
					(size 1.27 1.27)
				)
			)
		)
		(duplicate_pad_numbers_are_jumpers no)
		(fp_line
			(start -0.7874 0.4064)
			(end -0.7874 -0.4064)
			(stroke
				(width 0.1524)
				(type default)
			)
			(layer "F.SilkS")
		)
		(fp_line
			(start 0.7874 0.4064)
			(end -0.7874 0.4064)
			(stroke
				(width 0.1524)
				(type default)
			)
			(layer "F.SilkS")
		)
		(fp_line
			(start -0.7874 -0.4064)
			(end 0.7874 -0.4064)
			(stroke
				(width 0.1524)
				(type default)
			)
			(layer "F.SilkS")
		)
		(fp_line
			(start 0.7874 -0.4064)
			(end 0.7874 0.4064)
			(stroke
				(width 0.1524)
				(type default)
			)
			(layer "F.SilkS")
		)
		(fp_line
			(start -0.67945 0.3048)
			(end -0.67945 -0.305054)
			(stroke
				(width 0.1)
				(type default)
			)
			(layer "F.Fab")
		)
		(fp_line
			(start -0.12065 0.3048)
			(end -0.67945 0.3048)
			(stroke
				(width 0.1)
				(type default)
			)
			(layer "F.Fab")
		)
		(fp_line
			(start 0.120396 0.3048)
			(end 0.120396 0.2794)
			(stroke
				(width 0.1)
				(type default)
			)
			(layer "F.Fab")
		)
		(fp_line
			(start 0.67945 0.3048)
			(end 0.120396 0.3048)
			(stroke
				(width 0.1)
				(type default)
			)
			(layer "F.Fab")
		)
		(fp_line
			(start -0.12065 0.2794)
			(end -0.12065 0.3048)
			(stroke
				(width 0.1)
				(type default)
			)
			(layer "F.Fab")
		)
		(fp_line
			(start 0.120396 0.2794)
			(end -0.12065 0.2794)
			(stroke
				(width 0.1)
				(type default)
			)
			(layer "F.Fab")
		)
		(fp_line
			(start -0.12065 -0.2794)
			(end 0.12065 -0.2794)
			(stroke
				(width 0.1)
				(type default)
			)
			(layer "F.Fab")
		)
		(fp_line
			(start 0.12065 -0.2794)
			(end 0.12065 -0.3048)
			(stroke
				(width 0.1)
				(type default)
			)
			(layer "F.Fab")
		)
		(fp_line
			(start 0.12065 -0.3048)
			(end 0.67945 -0.3048)
			(stroke
				(width 0.1)
				(type default)
			)
			(layer "F.Fab")
		)
		(fp_line
			(start 0.67945 -0.3048)
			(end 0.67945 0.3048)
			(stroke
				(width 0.1)
				(type default)
			)
			(layer "F.Fab")
		)
		(fp_line
			(start -0.67945 -0.305054)
			(end -0.12065 -0.305054)
			(stroke
				(width 0.1)
				(type default)
			)
			(layer "F.Fab")
		)
		(fp_line
			(start -0.12065 -0.305054)
			(end -0.12065 -0.2794)
			(stroke
				(width 0.1)
				(type default)
			)
			(layer "F.Fab")
		)
		(pad "1" smd circle
			(at -0.40005 0 270)
			(size 0 0)
			(layers "F.Cu" "F.Mask" "F.Paste")
			(net "PVCCIN_CPU1")
		)
		(pad "2" smd circle
			(at 0.40005 0 270)
			(size 0 0)
			(layers "F.Cu" "F.Mask" "F.Paste")
			(net "GND")
		)
	)
	(footprint ""
		(layer "F.Cu")
		(at 448.61988 -94.602808 180)
		(property "Reference" "R4094"
			(at 0 0 180)
			(layer "F.SilkS")
			(hide yes)
			(effects
				(font
					(size 1.27 1.27)
				)
			)
		)
		(property "Value" ""
			(at 0 0 180)
			(layer "F.Fab")
			(effects
				(font
					(size 1.27 1.27)
				)
			)
		)
		(duplicate_pad_numbers_are_jumpers no)
		(fp_line
			(start 0.7874 0.4064)
			(end -0.7874 0.4064)
			(stroke
				(width 0.1524)
				(type default)
			)
			(layer "F.SilkS")
		)
		(fp_line
			(start 0.7874 -0.4064)
			(end 0.7874 0.4064)
			(stroke
				(width 0.1524)
				(type default)
			)
			(layer "F.SilkS")
		)
		(fp_line
			(start -0.7874 0.4064)
			(end -0.7874 -0.4064)
			(stroke
				(width 0.1524)
				(type default)
			)
			(layer "F.SilkS")
		)
		(fp_line
			(start -0.7874 -0.4064)
			(end 0.7874 -0.4064)
			(stroke
				(width 0.1524)
				(type default)
			)
			(layer "F.SilkS")
		)
		(fp_line
			(start 0.67945 0.3048)
			(end 0.120396 0.3048)
			(stroke
				(width 0.1)
				(type default)
			)
			(layer "F.Fab")
		)
		(fp_line
			(start 0.67945 -0.3048)
			(end 0.67945 0.3048)
			(stroke
				(width 0.1)
				(type default)
			)
			(layer "F.Fab")
		)
		(fp_line
			(start 0.12065 -0.2794)
			(end 0.12065 -0.3048)
			(stroke
				(width 0.1)
				(type default)
			)
			(layer "F.Fab")
		)
		(fp_line
			(start 0.12065 -0.3048)
			(end 0.67945 -0.3048)
			(stroke
				(width 0.1)
				(type default)
			)
			(layer "F.Fab")
		)
		(fp_line
			(start 0.120396 0.3048)
			(end 0.120396 0.2794)
			(stroke
				(width 0.1)
				(type default)
			)
			(layer "F.Fab")
		)
		(fp_line
			(start 0.120396 0.2794)
			(end -0.12065 0.2794)
			(stroke
				(width 0.1)
				(type default)
			)
			(layer "F.Fab")
		)
		(fp_line
			(start -0.12065 0.3048)
			(end -0.67945 0.3048)
			(stroke
				(width 0.1)
				(type default)
			)
			(layer "F.Fab")
		)
		(fp_line
			(start -0.12065 0.2794)
			(end -0.12065 0.3048)
			(stroke
				(width 0.1)
				(type default)
			)
			(layer "F.Fab")
		)
		(fp_line
			(start -0.12065 -0.2794)
			(end 0.12065 -0.2794)
			(stroke
				(width 0.1)
				(type default)
			)
			(layer "F.Fab")
		)
		(fp_line
			(start -0.12065 -0.305054)
			(end -0.12065 -0.2794)
			(stroke
				(width 0.1)
				(type default)
			)
			(layer "F.Fab")
		)
		(fp_line
			(start -0.67945 0.3048)
			(end -0.67945 -0.305054)
			(stroke
				(width 0.1)
				(type default)
			)
			(layer "F.Fab")
		)
		(fp_line
			(start -0.67945 -0.305054)
			(end -0.12065 -0.305054)
			(stroke
				(width 0.1)
				(type default)
			)
			(layer "F.Fab")
		)
		(pad "1" smd circle
			(at -0.40005 0 180)
			(size 0 0)
			(layers "F.Cu" "F.Mask" "F.Paste")
			(net "P3V3_AUX")
		)
		(pad "2" smd circle
			(at 0.40005 0 180)
			(size 0 0)
			(layers "F.Cu" "F.Mask" "F.Paste")
			(net "OCP_SFF_P3V3_ADC_ALERT_R")
		)
	)
)
